FILE_TYPE = CONNECTIVITY;
{Allegro Design Entry HDL 16.6-p007 (v16-6-112F) 10/10/2012}
"PAGE_NUMBER" = 138;
0"NC";
1"P3V3_STBY\g";
2"P3V3_STBY\g";
3"P3V3_STBY\g";
4"P3V3_STBY\g";
5"P3V3_STBY\g";
6"P3V3_STBY\g";
7"P3V3_STBY\g";
8"P3V3_STBY\g";
9"P3V3_STBY\g";
10"P3V3_STBY\g";
11"P3V3_STBY\g";
12"P3V3_STBY\g";
13"SMB_SENSOR_STBY_LVC3_SDA_R1";
14"SMB_SENSOR_STBY_LVC3_SCL_R1";
15"SMB_VR_STBY_LVC3_SDA_R1";
16"SMB_VR_STBY_LVC3_SCL_R1";
17"SMB_SENSOR_PCH_STBY_LVC3_SCL";
18"SMB_SENSOR_PCH_STBY_LVC3_SDA";
19"SMB_BMC_PMBUS_STBY_LVC3_SDA";
20"SMB_BMC_PMBUS_STBY_LVC3_SCL";
21"SMB_VR_STBY_LVC3_SCL";
22"SMB_VR_STBY_LVC3_SDA";
23"SMB_SMLINK0_STBY_LVC3_SCL";
24"SMB_SMLINK0_STBY_LVC3_SDA_R1";
25"SMB_HOST_STBY_LVC3_SCL";
26"SMB_HOST_STBY_LVC3_SDA";
27"SMB_SLOTX24_PCH_STBY_LVC3_SDA";
28"SMB_LAN_STBY_LVC3_SDA";
29"SMB_SLOTX24_PCH_STBY_LVC3_SCL";
30"SMB_SMLINK0_STBY_LVC3_SDA";
31"SMB_OCP_FRU_STBY_LVC3_SDA";
32"SMB_OCP_FRU_STBY_LVC3_SCL";
33"SMB_LAN_STBY_LVC3_SCL";
34"SMB_SMLINK0_STBY_LVC3_SCL_R1";
35"SMB_HOST_STBY_LVC3_SDA_R1";
36"SMB_HOST_STBY_LVC3_SCL_R1";
37"SMB_SLOTX24_STBY_LVC3_SDA_R1";
38"SMB_SLOTX24_STBY_LVC3_SCL_R1";
39"SMB_LAN_STBY_LVC3_SCL_R1";
40"SMB_LAN_STBY_LVC3_SDA_R1";
41"SMB_LAN_STBY_LVC3_SCL_R2";
42"SMB_LAN_STBY_LVC3_SDA_R2";
%"P3V3_STBY"
"1","(500,4725)","0","mstr_symbols","I138";
;
HDL_POWER"P3V3_STBY"
VOLTAGE"3.3V"
BODY_TYPE"PLUMBING"
SIZE"1B"
CDS_LIB"mstr_symbols";
"G\NAC"1;
%"P3V3_STBY"
"1","(850,4675)","0","mstr_symbols","I139";
;
HDL_POWER"P3V3_STBY"
VOLTAGE"3.3V"
CDS_LIB"mstr_symbols"
SIZE"1B"
BODY_TYPE"PLUMBING";
"G\NAC"2;
%"P3V3_STBY"
"1","(500,2825)","0","mstr_symbols","I140";
;
HDL_POWER"P3V3_STBY"
VOLTAGE"3.3V"
CDS_LIB"mstr_symbols"
BODY_TYPE"PLUMBING"
SIZE"1B";
"G\NAC"3;
%"P3V3_STBY"
"1","(875,2775)","0","mstr_symbols","I141";
;
HDL_POWER"P3V3_STBY"
VOLTAGE"3.3V"
BODY_TYPE"PLUMBING"
SIZE"1B"
CDS_LIB"mstr_symbols";
"G\NAC"4;
%"P3V3_STBY"
"1","(-3175,5200)","0","mstr_symbols","I144";
;
HDL_POWER"P3V3_STBY"
VOLTAGE"3.3V"
BODY_TYPE"PLUMBING"
CDS_LIB"mstr_symbols"
SIZE"1B";
"G\NAC"5;
%"P3V3_STBY"
"1","(-2775,5150)","0","mstr_symbols","I145";
;
HDL_POWER"P3V3_STBY"
VOLTAGE"3.3V"
BODY_TYPE"PLUMBING"
SIZE"1B"
CDS_LIB"mstr_symbols";
"G\NAC"6;
%"P3V3_STBY"
"1","(-3175,4250)","0","mstr_symbols","I146";
;
HDL_POWER"P3V3_STBY"
VOLTAGE"3.3V"
BODY_TYPE"PLUMBING"
CDS_LIB"mstr_symbols"
SIZE"1B";
"G\NAC"7;
%"P3V3_STBY"
"1","(-2775,4200)","0","mstr_symbols","I147";
;
HDL_POWER"P3V3_STBY"
VOLTAGE"3.3V"
BODY_TYPE"PLUMBING"
CDS_LIB"mstr_symbols"
SIZE"1B";
"G\NAC"8;
%"P3V3_STBY"
"1","(-3150,3200)","0","mstr_symbols","I148";
;
HDL_POWER"P3V3_STBY"
VOLTAGE"3.3V"
BODY_TYPE"PLUMBING"
CDS_LIB"mstr_symbols"
SIZE"1B";
"G\NAC"9;
%"P3V3_STBY"
"1","(-2750,3150)","0","mstr_symbols","I149";
;
HDL_POWER"P3V3_STBY"
VOLTAGE"3.3V"
SIZE"1B"
CDS_LIB"mstr_symbols"
BODY_TYPE"PLUMBING";
"G\NAC"10;
%"P3V3_STBY"
"1","(-3150,2300)","0","mstr_symbols","I150";
;
HDL_POWER"P3V3_STBY"
VOLTAGE"3.3V"
BODY_TYPE"PLUMBING"
CDS_LIB"mstr_symbols"
SIZE"1B";
"G\NAC"11;
%"P3V3_STBY"
"1","(-2750,2250)","0","mstr_symbols","I151";
;
HDL_POWER"P3V3_STBY"
VOLTAGE"3.3V"
SIZE"1B"
CDS_LIB"mstr_symbols"
BODY_TYPE"PLUMBING";
"G\NAC"12;
%"RES"
"1","(-3100,1325)","0","mstr_discrete","I158";
;
WATTAGE"1/16W"
CDS_LOCATION"R2U8"
CDS_LIB"mstr_discrete"
CDS_SEC"1"
$SEC"1"
PACK_TYPE"0402"
ROOM"SMBUS"
SKU"A"
BOM_COST"SM_CONTROLLER"
VALUE"20.0"
LOCATION"R2U8"
TOLERANCE"1%"
MATERIAL"EMPTY"
PART_NUMBER"G21796-173";
"B"
$PN"2"32;
"A"
$PN"1"33;
%"RES"
"1","(-3100,1425)","0","mstr_discrete","I159";
;
WATTAGE"1/16W"
CDS_LOCATION"R2U12"
CDS_LIB"mstr_discrete"
$SEC"1"
CDS_SEC"1"
PACK_TYPE"0402"
ROOM"SMBUS"
SKU"A"
BOM_COST"SM_CONTROLLER"
VALUE"20.0"
LOCATION"R2U12"
TOLERANCE"1%"
MATERIAL"EMPTY"
PART_NUMBER"G21796-173";
"B"
$PN"2"31;
"A"
$PN"1"28;
%"RES"
"1","(-275,3050)","0","mstr_discrete","I161";
;
CDS_SEC"1"
CDS_LIB"mstr_discrete"
ROOM"SMBUS"
CDS_LOCATION"R8D3"
SEC"1"
SEC_TYPE"0402"
BOM_COST"SM_CONTROLLER"
WATTAGE"1/16W"
PART_NUMBER"G21796-173"
MATERIAL"CHIP"
PACK_TYPE"0402"
TOLERANCE"1%"
LOCATION"R8D3"
VALUE"20.0";
"B"
$PN"2"17;
"A"
$PN"1"14;
%"RES"
"1","(-275,3225)","0","mstr_discrete","I162";
;
CDS_SEC"1"
CDS_LOCATION"R8D6"
CDS_LIB"mstr_discrete"
SEC"1"
ROOM"SMBUS"
BOM_COST"SM_CONTROLLER"
SEC_TYPE"0402"
TOLERANCE"1%"
PART_NUMBER"G21796-173"
MATERIAL"CHIP"
WATTAGE"1/16W"
PACK_TYPE"0402"
LOCATION"R8D6"
VALUE"20.0";
"B"
$PN"2"18;
"A"
$PN"1"13;
%"RES"
"1","(-275,2275)","0","mstr_discrete","I163";
;
CDS_SEC"1"
CDS_LIB"mstr_discrete"
ROOM"SMBUS"
SEC_TYPE"0402"
SEC"1"
CDS_LOCATION"R8D7"
BOM_COST"SM_CONTROLLER"
VALUE"20.0"
TOLERANCE"1%"
PACK_TYPE"0402"
WATTAGE"1/16W"
PART_NUMBER"G21796-173"
MATERIAL"CHIP"
LOCATION"R8D7";
"B"
$PN"2"22;
"A"
$PN"1"15;
%"RES"
"1","(-275,2125)","0","mstr_discrete","I164";
;
CDS_SEC"1"
CDS_LIB"mstr_discrete"
CDS_LOCATION"R8D4"
ROOM"SMBUS"
SEC_TYPE"0402"
BOM_COST"SM_CONTROLLER"
SEC"1"
TOLERANCE"1%"
VALUE"20.0"
LOCATION"R8D4"
WATTAGE"1/16W"
PACK_TYPE"0402"
MATERIAL"CHIP"
PART_NUMBER"G21796-173";
"B"
$PN"2"21;
"A"
$PN"1"16;
%"RES"
"1","(-3950,1775)","0","mstr_discrete","I165";
;
CDS_SEC"1"
CDS_LIB"mstr_discrete"
CDS_LOCATION"R2U9"
ROOM"SMBUS"
SEC"1"
SEC_TYPE"0402"
BOM_COST"SM_CONTROLLER"
VALUE"20.0"
TOLERANCE"1%"
LOCATION"R2U9"
PART_NUMBER"G21796-173"
MATERIAL"CHIP"
WATTAGE"1/16W"
PACK_TYPE"0402";
"B"
$PN"2"28;
"A"
$PN"1"40;
%"RES"
"1","(-3950,1625)","0","mstr_discrete","I166";
;
CDS_SEC"1"
CDS_LOCATION"R2U6"
CDS_LIB"mstr_discrete"
ROOM"SMBUS"
SEC_TYPE"0402"
BOM_COST"SM_CONTROLLER"
SEC"1"
VALUE"20.0"
TOLERANCE"1%"
LOCATION"R2U6"
PART_NUMBER"G21796-173"
MATERIAL"CHIP"
PACK_TYPE"0402"
WATTAGE"1/16W";
"B"
$PN"2"33;
"A"
$PN"1"39;
%"RES"
"1","(-3975,3700)","0","mstr_discrete","I167";
;
CDS_SEC"1"
CDS_LIB"mstr_discrete"
CDS_LOCATION"R8C20"
ROOM"SMBUS"
BOM_COST"SM_CONTROLLER"
SEC_TYPE"0402"
SEC"1"
VALUE"20.0"
TOLERANCE"1%"
LOCATION"R8C20"
PART_NUMBER"G21796-173"
MATERIAL"CHIP"
PACK_TYPE"0402"
WATTAGE"1/16W";
"B"
$PN"2"26;
"A"
$PN"1"35;
%"RES"
"1","(-3975,3550)","0","mstr_discrete","I168";
;
CDS_SEC"1"
CDS_LIB"mstr_discrete"
CDS_LOCATION"R8C14"
SEC"1"
SEC_TYPE"0402"
ROOM"SMBUS"
BOM_COST"SM_CONTROLLER"
VALUE"20.0"
TOLERANCE"1%"
LOCATION"R8C14"
PART_NUMBER"G21796-173"
MATERIAL"CHIP"
PACK_TYPE"0402"
WATTAGE"1/16W";
"B"
$PN"2"25;
"A"
$PN"1"36;
%"RES"
"1","(-3975,4625)","0","mstr_discrete","I169";
;
CDS_SEC"1"
CDS_LOCATION"R8C11"
CDS_LIB"mstr_discrete"
ROOM"SMBUS"
SEC"1"
SEC_TYPE"0402"
BOM_COST"SM_CONTROLLER"
VALUE"20.0"
TOLERANCE"1%"
LOCATION"R8C11"
PART_NUMBER"G21796-173"
MATERIAL"CHIP"
PACK_TYPE"0402"
WATTAGE"1/16W";
"B"
$PN"2"30;
"A"
$PN"1"24;
%"RES"
"1","(-3975,4475)","0","mstr_discrete","I170";
;
CDS_SEC"1"
CDS_LOCATION"R8C12"
CDS_LIB"mstr_discrete"
ROOM"SMBUS"
SEC_TYPE"0402"
SEC"1"
BOM_COST"SM_CONTROLLER"
VALUE"20.0"
PART_NUMBER"G21796-173"
MATERIAL"CHIP"
PACK_TYPE"0402"
WATTAGE"1/16W"
LOCATION"R8C12"
TOLERANCE"1%";
"B"
$PN"2"23;
"A"
$PN"1"34;
%"RES"
"1","(-3975,2150)","0","mstr_discrete","I171";
;
CDS_SEC"1"
CDS_LIB"mstr_discrete"
CDS_LOCATION"R2N20"
ROOM"SMBUS"
SEC_TYPE"0402"
BOM_COST"SM_CONTROLLER"
SEC"1"
VALUE"0.0"
TOLERANCE"5%"
LOCATION"R2N20"
PART_NUMBER"G21497-005"
MATERIAL"CHIP"
PACK_TYPE"0402"
WATTAGE"1/16W";
"B"
$PN"2"28;
"A"
$PN"1"42;
%"RES"
"1","(-3950,2650)","0","mstr_discrete","I173";
;
CDS_SEC"1"
CDS_LOCATION"R8B27"
CDS_LIB"mstr_discrete"
ROOM"SMBUS"
BOM_COST"SM_CONTROLLER"
SEC_TYPE"0402"
SEC"1"
VALUE"20.0"
TOLERANCE"1%"
LOCATION"R8B27"
PART_NUMBER"G21796-173"
MATERIAL"CHIP"
PACK_TYPE"0402"
WATTAGE"1/16W";
"B"
$PN"2"27;
"A"
$PN"1"37;
%"RES"
"1","(-3950,2500)","0","mstr_discrete","I174";
;
CDS_SEC"1"
CDS_LIB"mstr_discrete"
CDS_LOCATION"R8B28"
ROOM"SMBUS"
SEC"1"
SEC_TYPE"0402"
BOM_COST"SM_CONTROLLER"
VALUE"20.0"
TOLERANCE"1%"
LOCATION"R8B28"
PART_NUMBER"G21796-173"
MATERIAL"CHIP"
PACK_TYPE"0402"
WATTAGE"1/16W";
"B"
$PN"2"29;
"A"
$PN"1"38;
%"RES"
"1","(-3975,2000)","0","mstr_discrete","I175";
;
CDS_SEC"1"
CDS_LIB"mstr_discrete"
CDS_LOCATION"R2N21"
ROOM"SMBUS"
SEC_TYPE"0402"
BOM_COST"SM_CONTROLLER"
SEC"1"
VALUE"0.0"
LOCATION"R2N21"
MATERIAL"CHIP"
TOLERANCE"5%"
PART_NUMBER"G21497-005"
PACK_TYPE"0402"
WATTAGE"1/16W";
"B"
$PN"2"33;
"A"
$PN"1"41;
%"RES"
"2","(500,4450)","0","mstr_discrete","I83";
;
CDS_SEC"1"
CDS_LIB"mstr_discrete"
CDS_LOCATION"R2T53"
ROOM"SMBUS"
SEC"1"
SEC_TYPE"0402"
BOM_COST"SM_CONTROLLER"
LOCATION"R2T53"
PART_NUMBER"G21796-235"
PACK_TYPE"0402"
WATTAGE"1/16W"
VALUE"665"
MATERIAL"CHIP"
TOLERANCE"1.0%";
"A"
$PN"1"1;
"B"
$PN"2"19;
%"RES"
"2","(850,4400)","0","mstr_discrete","I84";
;
CDS_SEC"1"
CDS_LIB"mstr_discrete"
CDS_LOCATION"R2T54"
ROOM"SMBUS"
SEC"1"
SEC_TYPE"0402"
BOM_COST"SM_CONTROLLER"
PACK_TYPE"0402"
MATERIAL"CHIP"
VALUE"665"
TOLERANCE"1.0%"
LOCATION"R2T54"
PART_NUMBER"G21796-235"
WATTAGE"1/16W";
"A"
$PN"1"2;
"B"
$PN"2"20;
%"RES"
"2","(500,2575)","0","mstr_discrete","I87";
;
CDS_SEC"1"
$SEC"1"
CDS_LIB"mstr_discrete"
BOM_COST"SM_CONTROLLER"
CDS_LOCATION"R8D17"
ROOM"SMBUS"
TOLERANCE"1%"
PACK_TYPE"0402"
MATERIAL"CHIP"
PART_NUMBER"G21796-095"
WATTAGE"1/16W"
VALUE"1.37K"
LOCATION"R8D17";
"A"
$PN"1"3;
"B"
$PN"2"22;
%"RES"
"2","(875,2525)","0","mstr_discrete","I88";
;
CDS_SEC"1"
$SEC"1"
CDS_LIB"mstr_discrete"
ROOM"SMBUS"
CDS_LOCATION"R8D15"
BOM_COST"SM_CONTROLLER"
LOCATION"R8D15"
TOLERANCE"1%"
PART_NUMBER"G21796-095"
VALUE"1.37K"
PACK_TYPE"0402"
MATERIAL"CHIP"
WATTAGE"1/16W";
"A"
$PN"1"4;
"B"
$PN"2"21;
%"RES"
"2","(-3175,4950)","0","mstr_discrete","I89";
;
CDS_SEC"1"
CDS_LIB"mstr_discrete"
CDS_LOCATION"R2N8"
ROOM"SMBUS"
SEC"1"
SEC_TYPE"0402"
BOM_COST"SM_CONTROLLER"
LOCATION"R2N8"
PART_NUMBER"G21796-235"
VALUE"665"
TOLERANCE"1.0%"
PACK_TYPE"0402"
MATERIAL"CHIP"
WATTAGE"1/16W";
"A"
$PN"1"5;
"B"
$PN"2"30;
%"RES"
"2","(-2775,4900)","0","mstr_discrete","I90";
;
CDS_SEC"1"
CDS_LIB"mstr_discrete"
CDS_LOCATION"R2N5"
ROOM"SMBUS"
BOM_COST"SM_CONTROLLER"
SEC_TYPE"0402"
SEC"1"
LOCATION"R2N5"
PART_NUMBER"G21796-235"
PACK_TYPE"0402"
MATERIAL"CHIP"
WATTAGE"1/16W"
VALUE"665"
TOLERANCE"1.0%";
"A"
$PN"1"6;
"B"
$PN"2"23;
%"RES"
"2","(-3175,4025)","0","mstr_discrete","I91";
;
CDS_SEC"1"
$SEC"1"
CDS_LIB"mstr_discrete"
ROOM"SMBUS"
CDS_LOCATION"R8C16"
BOM_COST"SM_CONTROLLER"
PART_NUMBER"G21796-001"
TOLERANCE"1%"
PACK_TYPE"0402"
MATERIAL"CHIP"
WATTAGE"1/16W"
LOCATION"R8C16"
VALUE"2.0K";
"A"
$PN"1"7;
"B"
$PN"2"26;
%"RES"
"2","(-2775,3975)","0","mstr_discrete","I92";
;
CDS_SEC"1"
$SEC"1"
CDS_LIB"mstr_discrete"
ROOM"SMBUS"
BOM_COST"SM_CONTROLLER"
CDS_LOCATION"R8C15"
PACK_TYPE"0402"
WATTAGE"1/16W"
MATERIAL"CHIP"
VALUE"2.0K"
TOLERANCE"1%"
PART_NUMBER"G21796-001"
LOCATION"R8C15";
"A"
$PN"1"8;
"B"
$PN"2"25;
%"RES"
"2","(-3150,2950)","0","mstr_discrete","I95";
;
CDS_SEC"1"
CDS_LIB"mstr_discrete"
CDS_LOCATION"R8B24"
ROOM"SMBUS"
SEC_TYPE"0402"
SEC"1"
BOM_COST"SM_CONTROLLER"
PART_NUMBER"G21497-013"
VALUE"3.3K"
TOLERANCE"5%"
PACK_TYPE"0402"
MATERIAL"CHIP"
WATTAGE"1/16W"
LOCATION"R8B24";
"A"
$PN"1"9;
"B"
$PN"2"27;
%"RES"
"2","(-2750,2925)","0","mstr_discrete","I96";
;
CDS_SEC"1"
CDS_LIB"mstr_discrete"
CDS_LOCATION"R8B26"
ROOM"SMBUS"
SEC_TYPE"0402"
BOM_COST"SM_CONTROLLER"
SEC"1"
PACK_TYPE"0402"
TOLERANCE"5%"
MATERIAL"CHIP"
WATTAGE"1/16W"
VALUE"3.3K"
LOCATION"R8B26"
PART_NUMBER"G21497-013";
"A"
$PN"1"10;
"B"
$PN"2"29;
%"RES"
"2","(-3150,2100)","0","mstr_discrete","I97";
;
CDS_SEC"1"
CDS_LIB"mstr_discrete"
CDS_LOCATION"R2U11"
ROOM"SMBUS"
BOM_COST"SM_CONTROLLER"
SEC_TYPE"0402"
SEC"1"
PACK_TYPE"0402"
PART_NUMBER"G21796-235"
MATERIAL"CHIP"
VALUE"665"
TOLERANCE"1.0%"
WATTAGE"1/16W"
LOCATION"R2U11";
"A"
$PN"1"11;
"B"
$PN"2"28;
%"RES"
"2","(-2750,2025)","0","mstr_discrete","I98";
;
CDS_SEC"1"
CDS_LIB"mstr_discrete"
CDS_LOCATION"R2U3"
SEC"1"
ROOM"SMBUS"
SEC_TYPE"0402"
BOM_COST"SM_CONTROLLER"
PART_NUMBER"G21796-235"
PACK_TYPE"0402"
MATERIAL"CHIP"
WATTAGE"1/16W"
TOLERANCE"1.0%"
LOCATION"R2U3"
VALUE"665";
"A"
$PN"1"12;
"B"
$PN"2"33;
END.
